# BASEBOARD_FAB2 (Tioga Pass) — schematic netlist excerpt (pin names and nets, part order shuffled) for the footprints in the layout excerpt that follows; sources: Cadence DE-HDL packaged netlist, KiCad conversion of Wiwynn_Tioga_Pass_MB.brd

C3D7  CAP_A  22.0UF 4V 20% X6S  pkg 0603V  page 76 : A = PVCCMCP_CPU1 ; B = GND
C9W7  CAP_A  0.1UF 16V 10% X7R  pkg 0402V  page 248 : A = P3V3_STBY ; B = GND
C5B1  CAP_A  47UF 4V 20% X5R  pkg 0603V  page 220 : A = PVDDQ_DEF ; B = GND

(kicad_pcb
	(version 20260206)
	(generator "pcbnew")
	(generator_version "10.0")
	(general
		(thickness 1.6)
		(legacy_teardrops no)
	)
	(paper "A4")
	(title_block
		(title "Wiwynn_Tioga_Pass_MB.brd")
		(comment 1 "Tioga Pass / footprints 1052-1054 of 4770")
	)
	(layers
		(0 "F.Cu" signal "TOP")
		(4 "In1.Cu" signal "L2GND")
		(6 "In2.Cu" signal "L3")
		(8 "In3.Cu" signal "L4GND")
		(10 "In4.Cu" signal "L5")
		(12 "In5.Cu" signal "L6GND")
		(14 "In6.Cu" signal "L7VCC")
		(16 "In7.Cu" signal "L8VCC")
		(18 "In8.Cu" signal "L9GND")
		(20 "In9.Cu" signal "L10")
		(22 "In10.Cu" signal "L11GND")
		(24 "In11.Cu" signal "L12")
		(26 "In12.Cu" signal "L13GND")
		(2 "B.Cu" signal "BOTTOM")
		(9 "F.Adhes" user "F.Adhesive")
		(11 "B.Adhes" user "B.Adhesive")
		(13 "F.Paste" user "Package Geometry/Pastemask Top")
		(15 "B.Paste" user "Package Geometry/Pastemask Bottom")
		(5 "F.SilkS" user "Ref Des/Silkscreen Top")
		(7 "B.SilkS" user "Ref Des/Silkscreen Bottom")
		(1 "F.Mask" user "Board Geometry/Soldermask Top")
		(3 "B.Mask" user "Board Geometry/Soldermask Bottom")
		(17 "Dwgs.User" user "User.Drawings")
		(19 "Cmts.User" user "User.Comments")
		(21 "Eco1.User" user "User.Eco1")
		(23 "Eco2.User" user "User.Eco2")
		(25 "Edge.Cuts" user "Board Geometry/Outline")
		(27 "Margin" user)
		(31 "F.CrtYd" user "Package Geometry/Place Bound Top")
		(29 "B.CrtYd" user "Package Geometry/Place Bound Bottom")
		(35 "F.Fab" user "Ref Des/Assembly Top")
		(33 "B.Fab" user "Ref Des/Assembly Bottom")
	)
	(footprint ""
		(layer "F.Cu")
		(at 112.062768 -79.6036 180)
		(property "Reference" "C3D7"
			(at 0 0 180)
			(layer "F.SilkS")
			(hide yes)
			(effects
				(font
					(size 1.27 1.27)
				)
			)
		)
		(property "Value" ""
			(at 0 0 180)
			(layer "F.Fab")
			(effects
				(font
					(size 1.27 1.27)
				)
			)
		)
		(duplicate_pad_numbers_are_jumpers no)
		(fp_poly
			(pts
				(xy -0.4953 -0.2032) (xy 0.4953 -0.2032) (xy 0.4953 1.6002) (xy -0.4953 1.6002)
			)
			(stroke
				(width 0)
				(type default)
			)
			(fill no)
			(layer "F.CrtYd")
		)
		(fp_line
			(start 0.4953 1.6002)
			(end -0.4953 1.6002)
			(stroke
				(width 0.1)
				(type default)
			)
			(layer "F.Fab")
		)
		(fp_line
			(start 0.4953 -0.2032)
			(end 0.4953 1.6002)
			(stroke
				(width 0.1)
				(type default)
			)
			(layer "F.Fab")
		)
		(fp_line
			(start -0.4953 1.6002)
			(end -0.4953 -0.2032)
			(stroke
				(width 0.1)
				(type default)
			)
			(layer "F.Fab")
		)
		(fp_line
			(start -0.4953 -0.2032)
			(end 0.4953 -0.2032)
			(stroke
				(width 0.1)
				(type default)
			)
			(layer "F.Fab")
		)
		(pad "1" smd rect
			(at 0 0 180)
			(size 0.762 0.889)
			(layers "F.Cu" "F.Mask" "F.Paste")
			(net "PVCCMCP_CPU1")
		)
		(pad "2" smd rect
			(at 0 1.397 180)
			(size 0.762 0.889)
			(layers "F.Cu" "F.Mask" "F.Paste")
			(net "GND")
		)
		(zone
			(layer "F.Cu")
			(hatch none 0.5)
			(connect_pads
				(clearance 0)
			)
			(min_thickness 0.25)
			(keepout
				(tracks not_allowed)
				(vias allowed)
				(pads allowed)
				(copperpour not_allowed)
				(footprints allowed)
			)
			(placement
				(enabled no)
				(sheetname "")
			)
			(fill
				(thermal_gap 0.5)
				(thermal_bridge_width 0.5)
				(island_removal_mode 0)
			)
			(polygon
				(pts
					(xy 112.443768 -80.0481) (xy 111.681768 -80.0481) (xy 111.681768 -80.5561) (xy 112.443768 -80.5561)
				)
			)
		)
	)
	(footprint ""
		(layer "F.Cu")
		(at 261.747 -129.859024)
		(property "Reference" "C5B1"
			(at 0 0 0)
			(layer "F.SilkS")
			(hide yes)
			(effects
				(font
					(size 1.27 1.27)
				)
			)
		)
		(property "Value" ""
			(at 0 0 0)
			(layer "F.Fab")
			(effects
				(font
					(size 1.27 1.27)
				)
			)
		)
		(duplicate_pad_numbers_are_jumpers no)
		(fp_rect
			(start -0.500126 1.598422)
			(end 0.500126 -0.201422)
			(stroke
				(width 0)
				(type default)
			)
			(fill no)
			(layer "F.CrtYd")
		)
		(fp_line
			(start -0.500126 -0.201422)
			(end 0.500126 -0.201422)
			(stroke
				(width 0.1)
				(type default)
			)
			(layer "F.Fab")
		)
		(fp_line
			(start -0.500126 1.598422)
			(end -0.500126 -0.201422)
			(stroke
				(width 0.1)
				(type default)
			)
			(layer "F.Fab")
		)
		(fp_line
			(start 0.500126 -0.201422)
			(end 0.500126 1.598422)
			(stroke
				(width 0.1)
				(type default)
			)
			(layer "F.Fab")
		)
		(fp_line
			(start 0.500126 1.598422)
			(end -0.500126 1.598422)
			(stroke
				(width 0.1)
				(type default)
			)
			(layer "F.Fab")
		)
		(pad "1" smd rect
			(at 0 0 270)
			(size 0.889 0.9906)
			(layers "F.Cu" "F.Mask" "F.Paste")
			(net "PVDDQ_DEF")
		)
		(pad "2" smd rect
			(at 0 1.397 270)
			(size 0.889 0.9906)
			(layers "F.Cu" "F.Mask" "F.Paste")
			(net "GND")
		)
		(zone
			(layer "F.Cu")
			(hatch none 0.5)
			(connect_pads
				(clearance 0)
			)
			(min_thickness 0.25)
			(keepout
				(tracks allowed)
				(vias not_allowed)
				(pads allowed)
				(copperpour not_allowed)
				(footprints allowed)
			)
			(placement
				(enabled no)
				(sheetname "")
			)
			(fill
				(thermal_gap 0.5)
				(thermal_bridge_width 0.5)
				(island_removal_mode 0)
			)
			(polygon
				(pts
					(xy 261.2517 -128.906524) (xy 262.2423 -128.906524) (xy 262.2423 -129.414524) (xy 261.2517 -129.414524)
				)
			)
		)
		(zone
			(layer "F.Cu")
			(hatch none 0.5)
			(connect_pads
				(clearance 0)
			)
			(min_thickness 0.25)
			(keepout
				(tracks not_allowed)
				(vias allowed)
				(pads allowed)
				(copperpour not_allowed)
				(footprints allowed)
			)
			(placement
				(enabled no)
				(sheetname "")
			)
			(fill
				(thermal_gap 0.5)
				(thermal_bridge_width 0.5)
				(island_removal_mode 0)
			)
			(polygon
				(pts
					(xy 261.2517 -128.906524) (xy 262.2423 -128.906524) (xy 262.2423 -129.414524) (xy 261.2517 -129.414524)
				)
			)
		)
	)
	(footprint ""
		(layer "F.Cu")
		(at 399.932144 -40.404542 -90)
		(property "Reference" "C9W7"
			(at -0.8382 -0.67818 270)
			(unlocked yes)
			(layer "F.SilkS")
			(effects
				(font
					(size 0.4064 0.254)
					(thickness 0.1524)
				)
				(justify left)
			)
		)
		(property "Value" ""
			(at 0 0 270)
			(layer "F.Fab")
			(effects
				(font
					(size 1.27 1.27)
				)
			)
		)
		(duplicate_pad_numbers_are_jumpers no)
		(fp_poly
			(pts
				(xy 0.3048 -0.1016) (xy 0.3048 0.9906) (xy -0.3048 0.9906) (xy -0.3048 -0.1016)
			)
			(stroke
				(width 0)
				(type default)
			)
			(fill no)
			(layer "F.CrtYd")
		)
		(fp_line
			(start -0.3048 0.9906)
			(end 0.3048 0.9906)
			(stroke
				(width 0.1)
				(type default)
			)
			(layer "F.Fab")
		)
		(fp_line
			(start 0.3048 0.9906)
			(end 0.3048 -0.1016)
			(stroke
				(width 0.1)
				(type default)
			)
			(layer "F.Fab")
		)
		(fp_line
			(start -0.3048 -0.1016)
			(end -0.3048 0.9906)
			(stroke
				(width 0.1)
				(type default)
			)
			(layer "F.Fab")
		)
		(fp_line
			(start 0.3048 -0.1016)
			(end -0.3048 -0.1016)
			(stroke
				(width 0.1)
				(type default)
			)
			(layer "F.Fab")
		)
		(pad "1" smd rect
			(at 0 0 270)
			(size 0.508 0.508)
			(layers "F.Cu" "F.Mask" "F.Paste")
			(net "P3V3_STBY")
		)
		(pad "2" smd rect
			(at 0 0.889 270)
			(size 0.508 0.508)
			(layers "F.Cu" "F.Mask" "F.Paste")
			(net "GND")
		)
		(zone
			(layer "F.Cu")
			(hatch none 0.5)
			(connect_pads
				(clearance 0)
			)
			(min_thickness 0.25)
			(keepout
				(tracks not_allowed)
				(vias allowed)
				(pads allowed)
				(copperpour not_allowed)
				(footprints allowed)
			)
			(placement
				(enabled no)
				(sheetname "")
			)
			(fill
				(thermal_gap 0.5)
				(thermal_bridge_width 0.5)
				(island_removal_mode 0)
			)
			(polygon
				(pts
					(xy 399.297144 -40.658542) (xy 399.297144 -40.150542) (xy 399.678144 -40.150542) (xy 399.678144 -40.658542)
				)
			)
		)
		(zone
			(layer "F.Cu")
			(hatch none 0.5)
			(connect_pads
				(clearance 0)
			)
			(min_thickness 0.25)
			(keepout
				(tracks allowed)
				(vias not_allowed)
				(pads allowed)
				(copperpour not_allowed)
				(footprints allowed)
			)
			(placement
				(enabled no)
				(sheetname "")
			)
			(fill
				(thermal_gap 0.5)
				(thermal_bridge_width 0.5)
				(island_removal_mode 0)
			)
			(polygon
				(pts
					(xy 399.678144 -40.658542) (xy 399.678144 -40.150542) (xy 399.297144 -40.150542) (xy 399.297144 -40.658542)
				)
			)
		)
	)
)
